(kicad_pcb
	(version 20260206)
	(generator "pcbnew")
	(generator_version "10.0")
	(general
		(thickness 1.6)
		(legacy_teardrops no)
	)
	(paper "A4")
	(title_block
		(title "Bryce Canyon_IOM_IOC_16318-2_OCP.brd")
		(comment 1 "Bryce Canyon / footprints 518-521 of 1605")
	)
	(layers
		(0 "F.Cu" signal "TOP")
		(4 "In1.Cu" signal "L2GND")
		(6 "In2.Cu" signal "L3")
		(8 "In3.Cu" signal "L4VCC")
		(10 "In4.Cu" signal "L5VCC")
		(12 "In5.Cu" signal "L6")
		(14 "In6.Cu" signal "L7GND")
		(2 "B.Cu" signal "BOTTOM")
		(9 "F.Adhes" user "F.Adhesive")
		(11 "B.Adhes" user "B.Adhesive")
		(13 "F.Paste" user "Package Geometry/Pastemask Top")
		(15 "B.Paste" user "Package Geometry/Pastemask Bottom")
		(5 "F.SilkS" user "Ref Des/Silkscreen Top")
		(7 "B.SilkS" user "Ref Des/Silkscreen Bottom")
		(1 "F.Mask" user "Board Geometry/Soldermask Top")
		(3 "B.Mask" user "Board Geometry/Soldermask Bottom")
		(17 "Dwgs.User" user "User.Drawings")
		(19 "Cmts.User" user "User.Comments")
		(21 "Eco1.User" user "User.Eco1")
		(23 "Eco2.User" user "User.Eco2")
		(25 "Edge.Cuts" user "Board Geometry/Outline")
		(27 "Margin" user)
		(31 "F.CrtYd" user "Package Geometry/Place Bound Top")
		(29 "B.CrtYd" user "Package Geometry/Place Bound Bottom")
		(35 "F.Fab" user "Ref Des/Assembly Top")
		(33 "B.Fab" user "Ref Des/Assembly Bottom")
	)
	(footprint ""
		(layer "F.Cu")
		(at 192.772538 -49.977294)
		(property "Reference" "TP154"
			(at 0 0 0)
			(layer "F.SilkS")
			(hide yes)
			(effects
				(font
					(size 1.27 1.27)
				)
			)
		)
		(property "Value" "TPAD28-2-GP"
			(at -0.0127 -1.6637 0)
			(unlocked yes)
			(layer "F.Fab")
			(hide yes)
			(effects
				(font
					(size 1.016 1.016)
					(thickness 0.1524)
				)
			)
		)
		(property "Device Type" "TPAD28"
			(at -0.0127 -3.1877 0)
			(unlocked yes)
			(layer "F.Fab")
			(hide yes)
			(effects
				(font
					(size 1.016 1.016)
					(thickness 0.1524)
				)
			)
		)
		(duplicate_pad_numbers_are_jumpers no)
		(fp_poly
			(pts
				(arc
					(start 0.3556 0)
					(mid -0.3556 0)
					(end 0.3556 0)
				)
			)
			(stroke
				(width 0)
				(type default)
			)
			(fill no)
			(layer "F.CrtYd")
		)
		(fp_poly
			(pts
				(arc
					(start 0.6096 0)
					(mid -0.6096 0)
					(end 0.6096 0)
				)
			)
			(stroke
				(width 0)
				(type default)
			)
			(fill no)
			(layer "F.Fab")
		)
		(pad "1" smd circle
			(at 0 0)
			(size 0.7112 0.7112)
			(layers "F.Cu" "F.Mask" "F.Paste")
			(net "IOC_TRST_N")
		)
	)
	(footprint ""
		(layer "F.Cu")
		(at 51.5112 -129.5146)
		(property "Reference" "TP9"
			(at 0 0 0)
			(layer "F.SilkS")
			(hide yes)
			(effects
				(font
					(size 1.27 1.27)
				)
			)
		)
		(property "Value" "TPAD28-2-GP"
			(at -0.0127 -1.6637 0)
			(unlocked yes)
			(layer "F.Fab")
			(hide yes)
			(effects
				(font
					(size 1.016 1.016)
					(thickness 0.1524)
				)
			)
		)
		(property "Device Type" "TPAD28"
			(at -0.0127 -3.1877 0)
			(unlocked yes)
			(layer "F.Fab")
			(hide yes)
			(effects
				(font
					(size 1.016 1.016)
					(thickness 0.1524)
				)
			)
		)
		(duplicate_pad_numbers_are_jumpers no)
		(fp_poly
			(pts
				(arc
					(start 0.3556 0)
					(mid -0.3556 0)
					(end 0.3556 0)
				)
			)
			(stroke
				(width 0)
				(type default)
			)
			(fill no)
			(layer "F.CrtYd")
		)
		(fp_poly
			(pts
				(arc
					(start 0.6096 0)
					(mid -0.6096 0)
					(end 0.6096 0)
				)
			)
			(stroke
				(width 0)
				(type default)
			)
			(fill no)
			(layer "F.Fab")
		)
		(pad "1" smd circle
			(at 0 0)
			(size 0.7112 0.7112)
			(layers "F.Cu" "F.Mask" "F.Paste")
			(net "TP_BMC0_LPC_LAD0")
		)
	)
	(footprint ""
		(layer "F.Cu")
		(at 170.9039 -119.553736 90)
		(property "Reference" "R525"
			(at 0 0 90)
			(layer "F.SilkS")
			(hide yes)
			(effects
				(font
					(size 1.27 1.27)
				)
			)
		)
		(property "Value" "10KR2F-2-GP"
			(at 0.064008 -3.993896 90)
			(unlocked yes)
			(layer "F.Fab")
			(hide yes)
			(effects
				(font
					(size 1.016 1.016)
					(thickness 0.1524)
				)
			)
		)
		(property "Device Type" "R402H16"
			(at 0.064008 -5.517896 90)
			(unlocked yes)
			(layer "F.Fab")
			(hide yes)
			(effects
				(font
					(size 1.016 1.016)
					(thickness 0.1524)
				)
			)
		)
		(duplicate_pad_numbers_are_jumpers no)
		(fp_line
			(start 0.508 -0.9398)
			(end -0.508 -0.9398)
			(stroke
				(width 0.1524)
				(type default)
			)
			(layer "F.SilkS")
		)
		(fp_line
			(start -0.508 -0.9398)
			(end -0.508 0.9398)
			(stroke
				(width 0.1524)
				(type default)
			)
			(layer "F.SilkS")
		)
		(fp_rect
			(start -0.508 0.9398)
			(end 0.508 -0.9398)
			(stroke
				(width 0)
				(type default)
			)
			(fill no)
			(layer "F.CrtYd")
		)
		(fp_rect
			(start -0.508 0.9398)
			(end 0.508 -0.9398)
			(stroke
				(width 0)
				(type default)
			)
			(fill no)
			(layer "F.Fab")
		)
		(pad "1" smd custom
			(at 0 -0.4445 90)
			(size 0.1397 0.1397)
			(layers "F.Cu" "F.Mask" "F.Paste")
			(net "P12V_STBY")
			(options
				(clearance outline)
				(anchor circle)
			)
			(primitives
				(gr_poly
					(pts
						(arc
							(start -0.1778 -0.2794)
							(mid -0.249642 -0.249642)
							(end -0.2794 -0.1778)
						)
						(arc
							(start -0.2794 0.1778)
							(mid -0.249642 0.249642)
							(end -0.1778 0.2794)
						)
						(arc
							(start 0.1778 0.2794)
							(mid 0.249642 0.249642)
							(end 0.2794 0.1778)
						)
						(arc
							(start 0.2794 -0.1778)
							(mid 0.249642 -0.249642)
							(end 0.1778 -0.2794)
						)
					)
					(width 0)
					(fill yes)
				)
			)
		)
		(pad "2" smd custom
			(at 0 0.4445 90)
			(size 0.1397 0.1397)
			(layers "F.Cu" "F.Mask" "F.Paste")
			(net "PQ4_D")
			(options
				(clearance outline)
				(anchor circle)
			)
			(primitives
				(gr_poly
					(pts
						(arc
							(start -0.1778 -0.2794)
							(mid -0.249642 -0.249642)
							(end -0.2794 -0.1778)
						)
						(arc
							(start -0.2794 0.1778)
							(mid -0.249642 0.249642)
							(end -0.1778 0.2794)
						)
						(arc
							(start 0.1778 0.2794)
							(mid 0.249642 0.249642)
							(end 0.2794 0.1778)
						)
						(arc
							(start 0.2794 -0.1778)
							(mid 0.249642 -0.249642)
							(end 0.1778 -0.2794)
						)
					)
					(width 0)
					(fill yes)
				)
			)
		)
	)
	(footprint ""
		(layer "F.Cu")
		(at 12.94384 -13.41882 180)
		(property "Reference" "C529"
			(at 0 0 180)
			(layer "F.SilkS")
			(hide yes)
			(effects
				(font
					(size 1.27 1.27)
				)
			)
		)
		(property "Value" "SC1000P2KV6KX-GP-U"
			(at 0.0508 -3.5052 180)
			(unlocked yes)
			(layer "F.Fab")
			(hide yes)
			(effects
				(font
					(size 1.016 1.016)
					(thickness 0.1524)
				)
			)
		)
		(property "Device Type" "C1206H58"
			(at 0.0508 -5.0292 180)
			(unlocked yes)
			(layer "F.Fab")
			(hide yes)
			(effects
				(font
					(size 1.016 1.016)
					(thickness 0.1524)
				)
			)
		)
		(duplicate_pad_numbers_are_jumpers no)
		(fp_line
			(start 1.016 2.2352)
			(end -1.016 2.2352)
			(stroke
				(width 0.1524)
				(type default)
			)
			(layer "F.SilkS")
		)
		(fp_line
			(start 1.016 0.8382)
			(end 1.016 2.2352)
			(stroke
				(width 0.1524)
				(type default)
			)
			(layer "F.SilkS")
		)
		(fp_line
			(start 1.016 -2.2352)
			(end 1.016 -0.8382)
			(stroke
				(width 0.1524)
				(type default)
			)
			(layer "F.SilkS")
		)
		(fp_line
			(start 1.016 -2.2352)
			(end -1.016 -2.2352)
			(stroke
				(width 0.1524)
				(type default)
			)
			(layer "F.SilkS")
		)
		(fp_line
			(start -1.016 2.2352)
			(end -1.016 0.8128)
			(stroke
				(width 0.1524)
				(type default)
			)
			(layer "F.SilkS")
		)
		(fp_line
			(start -1.016 -2.2352)
			(end -1.016 -0.8382)
			(stroke
				(width 0.1524)
				(type default)
			)
			(layer "F.SilkS")
		)
		(fp_rect
			(start -1.0922 2.3114)
			(end 1.0922 -2.3114)
			(stroke
				(width 0)
				(type default)
			)
			(fill no)
			(layer "F.CrtYd")
		)
		(fp_poly
			(pts
				(xy -1.0922 -2.3114) (xy 1.0922 -2.3114) (xy 1.0922 2.3114) (xy -1.0922 2.3114)
			)
			(stroke
				(width 0)
				(type default)
			)
			(fill no)
			(layer "F.Fab")
		)
		(pad "1" smd rect
			(at 0 -1.397 180)
			(size 1.651 1.27)
			(layers "F.Cu" "F.Mask" "F.Paste")
			(net "RST_BTN_GND")
		)
		(pad "2" smd rect
			(at 0 1.397 180)
			(size 1.651 1.27)
			(layers "F.Cu" "F.Mask" "F.Paste")
			(net "GND")
		)
	)
)
